# T6G (Grand Teton) — schematic netlist excerpt (pin names and nets, part order shuffled) for the footprints in the layout excerpt that follows; sources: Cadence DE-HDL packaged netlist, KiCad conversion of 04192023_DAF0TMB3IC0_F0TG_MB_C_brd_V02_OCP.brd

C2433  Q_CAP  22UF 4V 20% X6S  pkg C0402  page 74 : A = PVDDCR_SOC_P1 ; B = GND
C2465  Q_CAP  22UF 4V 20% X6S  pkg C0402  page 74 : A = PVDDCR_SOC_P1 ; B = GND
PC135  Q_CAP  22UF 16V 20% X6S  pkg C0805  page 192 : A = PVDD_33_S5 ; B = GND

(kicad_pcb
	(version 20260206)
	(generator "pcbnew")
	(generator_version "10.0")
	(general
		(thickness 1.6)
		(legacy_teardrops no)
	)
	(paper "A4")
	(title_block
		(title "04192023_DAF0TMB3IC0_F0TG_MB_C_brd_V02_OCP.brd")
		(comment 1 "Grand Teton / footprints 5697-5699 of 8354")
	)
	(layers
		(0 "F.Cu" signal "TOP")
		(4 "In1.Cu" signal "GND")
		(6 "In2.Cu" signal "IN1")
		(8 "In3.Cu" signal "GND1")
		(10 "In4.Cu" signal "IN2")
		(12 "In5.Cu" signal "GND2")
		(14 "In6.Cu" signal "IN3")
		(16 "In7.Cu" signal "GND3")
		(18 "In8.Cu" signal "VCC")
		(20 "In9.Cu" signal "VCC1")
		(22 "In10.Cu" signal "GND4")
		(24 "In11.Cu" signal "IN4")
		(26 "In12.Cu" signal "GND5")
		(28 "In13.Cu" signal "IN5")
		(30 "In14.Cu" signal "GND6")
		(32 "In15.Cu" signal "IN6")
		(34 "In16.Cu" signal "GND7")
		(2 "B.Cu" signal "BOTTOM")
		(9 "F.Adhes" user "F.Adhesive")
		(11 "B.Adhes" user "B.Adhesive")
		(13 "F.Paste" user "Package Geometry/Pastemask Top")
		(15 "B.Paste" user "Package Geometry/Pastemask Bottom")
		(5 "F.SilkS" user "Ref Des/Silkscreen Top")
		(7 "B.SilkS" user "Ref Des/Silkscreen Bottom")
		(1 "F.Mask" user "Board Geometry/Soldermask Top")
		(3 "B.Mask" user "Board Geometry/Soldermask Bottom")
		(17 "Dwgs.User" user "User.Drawings")
		(19 "Cmts.User" user "User.Comments")
		(21 "Eco1.User" user "User.Eco1")
		(23 "Eco2.User" user "User.Eco2")
		(25 "Edge.Cuts" user "Board Geometry/Outline")
		(27 "Margin" user)
		(31 "F.CrtYd" user "Package Geometry/Place Bound Top")
		(29 "B.CrtYd" user "Package Geometry/Place Bound Bottom")
		(35 "F.Fab" user "Ref Des/Assembly Top")
		(33 "B.Fab" user "Ref Des/Assembly Bottom")
	)
	(footprint ""
		(layer "B.Cu")
		(at 101.894386 -262.703564)
		(property "Reference" "C2465"
			(at 0 0 0)
			(layer "B.SilkS")
			(hide yes)
			(effects
				(font
					(size 1.27 1.27)
				)
				(justify mirror)
			)
		)
		(property "Value" ""
			(at 0 0 0)
			(layer "B.Fab")
			(effects
				(font
					(size 1.27 1.27)
				)
				(justify mirror)
			)
		)
		(duplicate_pad_numbers_are_jumpers no)
		(fp_line
			(start -0.7874 -0.4064)
			(end -0.7874 0.4064)
			(stroke
				(width 0.1524)
				(type default)
			)
			(layer "B.SilkS")
		)
		(fp_line
			(start -0.7874 0.4064)
			(end 0.7874 0.4064)
			(stroke
				(width 0.1524)
				(type default)
			)
			(layer "B.SilkS")
		)
		(fp_line
			(start 0.7874 -0.4064)
			(end -0.7874 -0.4064)
			(stroke
				(width 0.1524)
				(type default)
			)
			(layer "B.SilkS")
		)
		(fp_line
			(start 0.7874 0.4064)
			(end 0.7874 -0.4064)
			(stroke
				(width 0.1524)
				(type default)
			)
			(layer "B.SilkS")
		)
		(fp_line
			(start -0.67945 -0.3048)
			(end -0.67945 0.3048)
			(stroke
				(width 0.1)
				(type default)
			)
			(layer "B.Fab")
		)
		(fp_line
			(start -0.67945 0.3048)
			(end -0.120396 0.3048)
			(stroke
				(width 0.1)
				(type default)
			)
			(layer "B.Fab")
		)
		(fp_line
			(start -0.12065 -0.3048)
			(end -0.67945 -0.3048)
			(stroke
				(width 0.1)
				(type default)
			)
			(layer "B.Fab")
		)
		(fp_line
			(start -0.12065 -0.2794)
			(end -0.12065 -0.3048)
			(stroke
				(width 0.1)
				(type default)
			)
			(layer "B.Fab")
		)
		(fp_line
			(start -0.120396 0.2794)
			(end 0.12065 0.2794)
			(stroke
				(width 0.1)
				(type default)
			)
			(layer "B.Fab")
		)
		(fp_line
			(start -0.120396 0.3048)
			(end -0.120396 0.2794)
			(stroke
				(width 0.1)
				(type default)
			)
			(layer "B.Fab")
		)
		(fp_line
			(start 0.12065 -0.305054)
			(end 0.12065 -0.2794)
			(stroke
				(width 0.1)
				(type default)
			)
			(layer "B.Fab")
		)
		(fp_line
			(start 0.12065 -0.2794)
			(end -0.12065 -0.2794)
			(stroke
				(width 0.1)
				(type default)
			)
			(layer "B.Fab")
		)
		(fp_line
			(start 0.12065 0.2794)
			(end 0.12065 0.3048)
			(stroke
				(width 0.1)
				(type default)
			)
			(layer "B.Fab")
		)
		(fp_line
			(start 0.12065 0.3048)
			(end 0.67945 0.3048)
			(stroke
				(width 0.1)
				(type default)
			)
			(layer "B.Fab")
		)
		(fp_line
			(start 0.67945 -0.305054)
			(end 0.12065 -0.305054)
			(stroke
				(width 0.1)
				(type default)
			)
			(layer "B.Fab")
		)
		(fp_line
			(start 0.67945 0.3048)
			(end 0.67945 -0.305054)
			(stroke
				(width 0.1)
				(type default)
			)
			(layer "B.Fab")
		)
		(pad "1" smd circle
			(at 0.40005 0 180)
			(size 0 0)
			(layers "B.Cu" "B.Mask" "B.Paste")
			(net "PVDDCR_SOC_P1")
		)
		(pad "2" smd circle
			(at -0.40005 0 180)
			(size 0 0)
			(layers "B.Cu" "B.Mask" "B.Paste")
			(net "GND")
		)
	)
	(footprint ""
		(layer "B.Cu")
		(at 197.93712 -331.027786 -90)
		(property "Reference" "PC135"
			(at 0 0 90)
			(layer "B.SilkS")
			(hide yes)
			(effects
				(font
					(size 1.27 1.27)
				)
				(justify mirror)
			)
		)
		(property "Value" ""
			(at 0 0 90)
			(layer "B.Fab")
			(effects
				(font
					(size 1.27 1.27)
				)
				(justify mirror)
			)
		)
		(duplicate_pad_numbers_are_jumpers no)
		(fp_line
			(start -1.524 0.762)
			(end 1.524 0.762)
			(stroke
				(width 0.1524)
				(type default)
			)
			(layer "B.SilkS")
		)
		(fp_line
			(start 1.524 0.762)
			(end 1.524 -0.762)
			(stroke
				(width 0.1524)
				(type default)
			)
			(layer "B.SilkS")
		)
		(fp_line
			(start -1.524 -0.762)
			(end -1.524 0.762)
			(stroke
				(width 0.1524)
				(type default)
			)
			(layer "B.SilkS")
		)
		(fp_line
			(start 1.524 -0.762)
			(end -1.524 -0.762)
			(stroke
				(width 0.1524)
				(type default)
			)
			(layer "B.SilkS")
		)
		(fp_line
			(start -1.1049 0.724916)
			(end -1.1049 -0.724916)
			(stroke
				(width 0.1)
				(type default)
			)
			(layer "B.Fab")
		)
		(fp_line
			(start 1.1049 0.724916)
			(end -1.1049 0.724916)
			(stroke
				(width 0.1)
				(type default)
			)
			(layer "B.Fab")
		)
		(fp_line
			(start -1.1049 -0.724916)
			(end 1.1049 -0.724916)
			(stroke
				(width 0.1)
				(type default)
			)
			(layer "B.Fab")
		)
		(fp_line
			(start 1.1049 -0.724916)
			(end 1.1049 0.724916)
			(stroke
				(width 0.1)
				(type default)
			)
			(layer "B.Fab")
		)
		(pad "1" smd rect
			(at 0.889 0 270)
			(size 1.016 1.27)
			(layers "B.Cu" "B.Mask" "B.Paste")
			(net "PVDD_33_S5")
		)
		(pad "2" smd rect
			(at -0.889 0 270)
			(size 1.016 1.27)
			(layers "B.Cu" "B.Mask" "B.Paste")
			(net "GND")
		)
	)
	(footprint ""
		(layer "B.Cu")
		(at 110.856014 -257.74523 180)
		(property "Reference" "C2433"
			(at 0 0 0)
			(layer "B.SilkS")
			(hide yes)
			(effects
				(font
					(size 1.27 1.27)
				)
				(justify mirror)
			)
		)
		(property "Value" ""
			(at 0 0 0)
			(layer "B.Fab")
			(effects
				(font
					(size 1.27 1.27)
				)
				(justify mirror)
			)
		)
		(duplicate_pad_numbers_are_jumpers no)
		(fp_line
			(start 0.7874 0.4064)
			(end 0.7874 -0.4064)
			(stroke
				(width 0.1524)
				(type default)
			)
			(layer "B.SilkS")
		)
		(fp_line
			(start 0.7874 -0.4064)
			(end -0.7874 -0.4064)
			(stroke
				(width 0.1524)
				(type default)
			)
			(layer "B.SilkS")
		)
		(fp_line
			(start -0.7874 0.4064)
			(end 0.7874 0.4064)
			(stroke
				(width 0.1524)
				(type default)
			)
			(layer "B.SilkS")
		)
		(fp_line
			(start -0.7874 -0.4064)
			(end -0.7874 0.4064)
			(stroke
				(width 0.1524)
				(type default)
			)
			(layer "B.SilkS")
		)
		(fp_line
			(start 0.67945 0.3048)
			(end 0.67945 -0.305054)
			(stroke
				(width 0.1)
				(type default)
			)
			(layer "B.Fab")
		)
		(fp_line
			(start 0.67945 -0.305054)
			(end 0.12065 -0.305054)
			(stroke
				(width 0.1)
				(type default)
			)
			(layer "B.Fab")
		)
		(fp_line
			(start 0.12065 0.3048)
			(end 0.67945 0.3048)
			(stroke
				(width 0.1)
				(type default)
			)
			(layer "B.Fab")
		)
		(fp_line
			(start 0.12065 0.2794)
			(end 0.12065 0.3048)
			(stroke
				(width 0.1)
				(type default)
			)
			(layer "B.Fab")
		)
		(fp_line
			(start 0.12065 -0.2794)
			(end -0.12065 -0.2794)
			(stroke
				(width 0.1)
				(type default)
			)
			(layer "B.Fab")
		)
		(fp_line
			(start 0.12065 -0.305054)
			(end 0.12065 -0.2794)
			(stroke
				(width 0.1)
				(type default)
			)
			(layer "B.Fab")
		)
		(fp_line
			(start -0.120396 0.3048)
			(end -0.120396 0.2794)
			(stroke
				(width 0.1)
				(type default)
			)
			(layer "B.Fab")
		)
		(fp_line
			(start -0.120396 0.2794)
			(end 0.12065 0.2794)
			(stroke
				(width 0.1)
				(type default)
			)
			(layer "B.Fab")
		)
		(fp_line
			(start -0.12065 -0.2794)
			(end -0.12065 -0.3048)
			(stroke
				(width 0.1)
				(type default)
			)
			(layer "B.Fab")
		)
		(fp_line
			(start -0.12065 -0.3048)
			(end -0.67945 -0.3048)
			(stroke
				(width 0.1)
				(type default)
			)
			(layer "B.Fab")
		)
		(fp_line
			(start -0.67945 0.3048)
			(end -0.120396 0.3048)
			(stroke
				(width 0.1)
				(type default)
			)
			(layer "B.Fab")
		)
		(fp_line
			(start -0.67945 -0.3048)
			(end -0.67945 0.3048)
			(stroke
				(width 0.1)
				(type default)
			)
			(layer "B.Fab")
		)
		(pad "1" smd circle
			(at 0.40005 0)
			(size 0 0)
			(layers "B.Cu" "B.Mask" "B.Paste")
			(net "PVDDCR_SOC_P1")
		)
		(pad "2" smd circle
			(at -0.40005 0)
			(size 0 0)
			(layers "B.Cu" "B.Mask" "B.Paste")
			(net "GND")
		)
	)
)
